(kicad_pcb
	(version 20260206)
	(generator "pcbnew")
	(generator_version "10.0")
	(general
		(thickness 1.6)
		(legacy_teardrops no)
	)
	(paper "A4")
	(title_block
		(title "baseboard — 13948-1b.1110WZS1818.brd")
		(comment 1 "Honey Badger (Wiwynn) / footprints 1639-1644 of 2523")
	)
	(layers
		(0 "F.Cu" signal "TOP")
		(4 "In1.Cu" signal "L2GND")
		(6 "In2.Cu" signal "L3")
		(8 "In3.Cu" signal "L4VCC")
		(10 "In4.Cu" signal "L5VCC")
		(12 "In5.Cu" signal "L6")
		(14 "In6.Cu" signal "L7GND")
		(2 "B.Cu" signal "BOTTOM")
		(9 "F.Adhes" user "F.Adhesive")
		(11 "B.Adhes" user "B.Adhesive")
		(13 "F.Paste" user "Package Geometry/Pastemask Top")
		(15 "B.Paste" user "Package Geometry/Pastemask Bottom")
		(5 "F.SilkS" user "Ref Des/Silkscreen Top")
		(7 "B.SilkS" user "Ref Des/Silkscreen Bottom")
		(1 "F.Mask" user "Board Geometry/Soldermask Top")
		(3 "B.Mask" user "Board Geometry/Soldermask Bottom")
		(17 "Dwgs.User" user "User.Drawings")
		(19 "Cmts.User" user "User.Comments")
		(21 "Eco1.User" user "User.Eco1")
		(23 "Eco2.User" user "User.Eco2")
		(25 "Edge.Cuts" user "Board Geometry/Outline")
		(27 "Margin" user)
		(31 "F.CrtYd" user "Package Geometry/Place Bound Top")
		(29 "B.CrtYd" user "Package Geometry/Place Bound Bottom")
		(35 "F.Fab" user "Ref Des/Assembly Top")
		(33 "B.Fab" user "Ref Des/Assembly Bottom")
	)
	(footprint ""
		(layer "F.Cu")
		(at 289.678872 -72.716136 90)
		(property "Reference" "R522"
			(at 0 0 90)
			(layer "F.SilkS")
			(hide yes)
			(effects
				(font
					(size 1.27 1.27)
				)
			)
		)
		(property "Value" "10R2F-L-GP"
			(at 0.064008 -3.993896 90)
			(unlocked yes)
			(layer "F.Fab")
			(hide yes)
			(effects
				(font
					(size 1.016 1.016)
					(thickness 0.1524)
				)
			)
		)
		(property "Device Type" "R402H14"
			(at 0.064008 -5.517896 90)
			(unlocked yes)
			(layer "F.Fab")
			(hide yes)
			(effects
				(font
					(size 1.016 1.016)
					(thickness 0.1524)
				)
			)
		)
		(duplicate_pad_numbers_are_jumpers no)
		(fp_line
			(start 0.508 -0.9398)
			(end -0.508 -0.9398)
			(stroke
				(width 0.1524)
				(type default)
			)
			(layer "F.SilkS")
		)
		(fp_line
			(start -0.508 -0.9398)
			(end -0.508 0.9398)
			(stroke
				(width 0.1524)
				(type default)
			)
			(layer "F.SilkS")
		)
		(fp_rect
			(start -0.508 0.9398)
			(end 0.508 -0.9398)
			(stroke
				(width 0)
				(type default)
			)
			(fill no)
			(layer "F.CrtYd")
		)
		(fp_rect
			(start -0.508 0.9398)
			(end 0.508 -0.9398)
			(stroke
				(width 0)
				(type default)
			)
			(fill no)
			(layer "F.Fab")
		)
		(pad "1" smd custom
			(at 0 -0.4445 90)
			(size 0.1397 0.1397)
			(layers "F.Cu" "F.Mask" "F.Paste")
			(net "VR_HSC_GATE_MSB")
			(options
				(clearance outline)
				(anchor circle)
			)
			(primitives
				(gr_poly
					(pts
						(arc
							(start -0.1778 -0.2794)
							(mid -0.249642 -0.249642)
							(end -0.2794 -0.1778)
						)
						(arc
							(start -0.2794 0.1778)
							(mid -0.249642 0.249642)
							(end -0.1778 0.2794)
						)
						(arc
							(start 0.1778 0.2794)
							(mid 0.249642 0.249642)
							(end 0.2794 0.1778)
						)
						(arc
							(start 0.2794 -0.1778)
							(mid 0.249642 -0.249642)
							(end 0.1778 -0.2794)
						)
					)
					(width 0)
					(fill yes)
				)
			)
		)
		(pad "2" smd custom
			(at 0 0.4445 90)
			(size 0.1397 0.1397)
			(layers "F.Cu" "F.Mask" "F.Paste")
			(net "VR_HSC_GATE_R_MSB")
			(options
				(clearance outline)
				(anchor circle)
			)
			(primitives
				(gr_poly
					(pts
						(arc
							(start -0.1778 -0.2794)
							(mid -0.249642 -0.249642)
							(end -0.2794 -0.1778)
						)
						(arc
							(start -0.2794 0.1778)
							(mid -0.249642 0.249642)
							(end -0.1778 0.2794)
						)
						(arc
							(start 0.1778 0.2794)
							(mid 0.249642 0.249642)
							(end 0.2794 0.1778)
						)
						(arc
							(start 0.2794 -0.1778)
							(mid 0.249642 -0.249642)
							(end 0.1778 -0.2794)
						)
					)
					(width 0)
					(fill yes)
				)
			)
		)
	)
	(footprint ""
		(layer "F.Cu")
		(at 92.21597 -98.933 -90)
		(property "Reference" "SR778"
			(at 0 0 270)
			(layer "F.SilkS")
			(hide yes)
			(effects
				(font
					(size 1.27 1.27)
				)
			)
		)
		(property "Value" "4K7R2F-GP"
			(at 0.064008 -3.993896 270)
			(unlocked yes)
			(layer "F.Fab")
			(hide yes)
			(effects
				(font
					(size 1.016 1.016)
					(thickness 0.1524)
				)
			)
		)
		(property "Device Type" "R402H16"
			(at 0.064008 -5.517896 270)
			(unlocked yes)
			(layer "F.Fab")
			(hide yes)
			(effects
				(font
					(size 1.016 1.016)
					(thickness 0.1524)
				)
			)
		)
		(duplicate_pad_numbers_are_jumpers no)
		(fp_line
			(start -0.508 -0.9398)
			(end -0.508 0.9398)
			(stroke
				(width 0.1524)
				(type default)
			)
			(layer "F.SilkS")
		)
		(fp_line
			(start 0.508 -0.9398)
			(end -0.508 -0.9398)
			(stroke
				(width 0.1524)
				(type default)
			)
			(layer "F.SilkS")
		)
		(fp_rect
			(start -0.508 0.9398)
			(end 0.508 -0.9398)
			(stroke
				(width 0)
				(type default)
			)
			(fill no)
			(layer "F.CrtYd")
		)
		(fp_rect
			(start -0.508 0.9398)
			(end 0.508 -0.9398)
			(stroke
				(width 0)
				(type default)
			)
			(fill no)
			(layer "F.Fab")
		)
		(pad "1" smd custom
			(at 0 -0.4445 270)
			(size 0.1397 0.1397)
			(layers "F.Cu" "F.Mask" "F.Paste")
			(net "EXP_XM_ADDR_17")
			(options
				(clearance outline)
				(anchor circle)
			)
			(primitives
				(gr_poly
					(pts
						(arc
							(start -0.1778 -0.2794)
							(mid -0.249642 -0.249642)
							(end -0.2794 -0.1778)
						)
						(arc
							(start -0.2794 0.1778)
							(mid -0.249642 0.249642)
							(end -0.1778 0.2794)
						)
						(arc
							(start 0.1778 0.2794)
							(mid 0.249642 0.249642)
							(end 0.2794 0.1778)
						)
						(arc
							(start 0.2794 -0.1778)
							(mid 0.249642 -0.249642)
							(end 0.1778 -0.2794)
						)
					)
					(width 0)
					(fill yes)
				)
			)
		)
		(pad "2" smd custom
			(at 0 0.4445 270)
			(size 0.1397 0.1397)
			(layers "F.Cu" "F.Mask" "F.Paste")
			(net "GND")
			(options
				(clearance outline)
				(anchor circle)
			)
			(primitives
				(gr_poly
					(pts
						(arc
							(start -0.1778 -0.2794)
							(mid -0.249642 -0.249642)
							(end -0.2794 -0.1778)
						)
						(arc
							(start -0.2794 0.1778)
							(mid -0.249642 0.249642)
							(end -0.1778 0.2794)
						)
						(arc
							(start 0.1778 0.2794)
							(mid 0.249642 0.249642)
							(end 0.2794 0.1778)
						)
						(arc
							(start 0.2794 -0.1778)
							(mid 0.249642 -0.249642)
							(end 0.1778 -0.2794)
						)
					)
					(width 0)
					(fill yes)
				)
			)
		)
	)
	(footprint ""
		(layer "F.Cu")
		(at 332.359 -211.455 180)
		(property "Reference" "R5305"
			(at 0 0 180)
			(layer "F.SilkS")
			(hide yes)
			(effects
				(font
					(size 1.27 1.27)
				)
			)
		)
		(property "Value" "0R2J-2-GP"
			(at 0.064008 -3.993896 180)
			(unlocked yes)
			(layer "F.Fab")
			(hide yes)
			(effects
				(font
					(size 1.016 1.016)
					(thickness 0.1524)
				)
			)
		)
		(property "Device Type" "R402H16"
			(at 0.064008 -5.517896 180)
			(unlocked yes)
			(layer "F.Fab")
			(hide yes)
			(effects
				(font
					(size 1.016 1.016)
					(thickness 0.1524)
				)
			)
		)
		(duplicate_pad_numbers_are_jumpers no)
		(fp_line
			(start 0.508 -0.9398)
			(end -0.508 -0.9398)
			(stroke
				(width 0.1524)
				(type default)
			)
			(layer "F.SilkS")
		)
		(fp_line
			(start -0.508 -0.9398)
			(end -0.508 0.9398)
			(stroke
				(width 0.1524)
				(type default)
			)
			(layer "F.SilkS")
		)
		(fp_rect
			(start -0.508 0.9398)
			(end 0.508 -0.9398)
			(stroke
				(width 0)
				(type default)
			)
			(fill no)
			(layer "F.CrtYd")
		)
		(fp_rect
			(start -0.508 0.9398)
			(end 0.508 -0.9398)
			(stroke
				(width 0)
				(type default)
			)
			(fill no)
			(layer "F.Fab")
		)
		(pad "1" smd custom
			(at 0 -0.4445 180)
			(size 0.1397 0.1397)
			(layers "F.Cu" "F.Mask" "F.Paste")
			(net "EEPROM_SCL")
			(options
				(clearance outline)
				(anchor circle)
			)
			(primitives
				(gr_poly
					(pts
						(arc
							(start -0.1778 -0.2794)
							(mid -0.249642 -0.249642)
							(end -0.2794 -0.1778)
						)
						(arc
							(start -0.2794 0.1778)
							(mid -0.249642 0.249642)
							(end -0.1778 0.2794)
						)
						(arc
							(start 0.1778 0.2794)
							(mid 0.249642 0.249642)
							(end 0.2794 0.1778)
						)
						(arc
							(start 0.2794 -0.1778)
							(mid 0.249642 -0.249642)
							(end 0.1778 -0.2794)
						)
					)
					(width 0)
					(fill yes)
				)
			)
		)
		(pad "2" smd custom
			(at 0 0.4445 180)
			(size 0.1397 0.1397)
			(layers "F.Cu" "F.Mask" "F.Paste")
			(net "BMC_I2C_SCL_10")
			(options
				(clearance outline)
				(anchor circle)
			)
			(primitives
				(gr_poly
					(pts
						(arc
							(start -0.1778 -0.2794)
							(mid -0.249642 -0.249642)
							(end -0.2794 -0.1778)
						)
						(arc
							(start -0.2794 0.1778)
							(mid -0.249642 0.249642)
							(end -0.1778 0.2794)
						)
						(arc
							(start 0.1778 0.2794)
							(mid 0.249642 0.249642)
							(end 0.2794 0.1778)
						)
						(arc
							(start 0.2794 -0.1778)
							(mid 0.249642 -0.249642)
							(end 0.1778 -0.2794)
						)
					)
					(width 0)
					(fill yes)
				)
			)
		)
	)
	(footprint ""
		(layer "F.Cu")
		(at 185.284872 -206.497936 180)
		(property "Reference" "C242"
			(at 0 0 180)
			(layer "F.SilkS")
			(hide yes)
			(effects
				(font
					(size 1.27 1.27)
				)
			)
		)
		(property "Value" "SCD01U50V2KX-1GP"
			(at 1.1811 -2.7051 180)
			(unlocked yes)
			(layer "F.Fab")
			(hide yes)
			(effects
				(font
					(size 1.016 1.016)
					(thickness 0.1524)
				)
			)
		)
		(property "Device Type" "C402H22"
			(at 1.1811 -4.2291 180)
			(unlocked yes)
			(layer "F.Fab")
			(hide yes)
			(effects
				(font
					(size 1.016 1.016)
					(thickness 0.1524)
				)
			)
		)
		(duplicate_pad_numbers_are_jumpers no)
		(fp_rect
			(start -0.4318 0.9525)
			(end 0.4318 -0.9525)
			(stroke
				(width 0)
				(type default)
			)
			(fill no)
			(layer "F.CrtYd")
		)
		(fp_rect
			(start -0.4318 0.9525)
			(end 0.4318 -0.9525)
			(stroke
				(width 0)
				(type default)
			)
			(fill no)
			(layer "F.Fab")
		)
		(pad "1" smd custom
			(at 0 -0.4445 180)
			(size 0.1524 0.1524)
			(layers "F.Cu" "F.Mask" "F.Paste")
			(net "P3V3_STBY")
			(options
				(clearance outline)
				(anchor circle)
			)
			(primitives
				(gr_poly
					(pts
						(arc
							(start 0.3048 -0.2032)
							(mid 0.275042 -0.275042)
							(end 0.2032 -0.3048)
						)
						(arc
							(start -0.2032 -0.3048)
							(mid -0.275042 -0.275042)
							(end -0.3048 -0.2032)
						)
						(arc
							(start -0.3048 0.2032)
							(mid -0.275042 0.275042)
							(end -0.2032 0.3048)
						)
						(arc
							(start 0.2032 0.3048)
							(mid 0.275042 0.275042)
							(end 0.3048 0.2032)
						)
					)
					(width 0)
					(fill yes)
				)
			)
		)
		(pad "2" smd custom
			(at 0 0.4445 180)
			(size 0.1524 0.1524)
			(layers "F.Cu" "F.Mask" "F.Paste")
			(net "GND")
			(options
				(clearance outline)
				(anchor circle)
			)
			(primitives
				(gr_poly
					(pts
						(arc
							(start 0.3048 -0.2032)
							(mid 0.275042 -0.275042)
							(end 0.2032 -0.3048)
						)
						(arc
							(start -0.2032 -0.3048)
							(mid -0.275042 -0.275042)
							(end -0.3048 -0.2032)
						)
						(arc
							(start -0.3048 0.2032)
							(mid -0.275042 0.275042)
							(end -0.2032 0.3048)
						)
						(arc
							(start 0.2032 0.3048)
							(mid 0.275042 0.275042)
							(end 0.3048 0.2032)
						)
					)
					(width 0)
					(fill yes)
				)
			)
		)
	)
	(footprint ""
		(layer "F.Cu")
		(at 350.484948 -22.200108 180)
		(property "Reference" "SW2"
			(at 0 0 180)
			(layer "F.SilkS")
			(hide yes)
			(effects
				(font
					(size 1.27 1.27)
				)
			)
		)
		(property "Value" "SW-TACT-4P-196-GP"
			(at -5.5118 0.2032 180)
			(unlocked yes)
			(layer "F.Fab")
			(hide yes)
			(effects
				(font
					(size 1.016 1.016)
					(thickness 0.1524)
				)
			)
		)
		(property "Device Type" "DTS-63N-V"
			(at -5.5118 -1.3208 180)
			(unlocked yes)
			(layer "F.Fab")
			(hide yes)
			(effects
				(font
					(size 1.016 1.016)
					(thickness 0.1524)
				)
			)
		)
		(duplicate_pad_numbers_are_jumpers no)
		(fp_line
			(start 4.2164 3.3528)
			(end 4.2164 -3.3528)
			(stroke
				(width 0.1524)
				(type default)
			)
			(layer "F.SilkS")
		)
		(fp_line
			(start 4.2164 -3.3528)
			(end -4.2164 -3.3528)
			(stroke
				(width 0.1524)
				(type default)
			)
			(layer "F.SilkS")
		)
		(fp_line
			(start 0 0.762)
			(end 0 2.54)
			(stroke
				(width 0.1524)
				(type default)
			)
			(layer "F.SilkS")
		)
		(fp_line
			(start 0 -0.762)
			(end 0.508 0.508)
			(stroke
				(width 0.1524)
				(type default)
			)
			(layer "F.SilkS")
		)
		(fp_line
			(start 0 -2.54)
			(end 0 -0.762)
			(stroke
				(width 0.1524)
				(type default)
			)
			(layer "F.SilkS")
		)
		(fp_line
			(start -3.2258 -3.6322)
			(end -4.4958 -3.6322)
			(stroke
				(width 0.4064)
				(type default)
			)
			(layer "F.SilkS")
		)
		(fp_line
			(start -4.2164 3.3528)
			(end 4.2164 3.3528)
			(stroke
				(width 0.1524)
				(type default)
			)
			(layer "F.SilkS")
		)
		(fp_line
			(start -4.2164 -3.3528)
			(end -4.2164 3.3528)
			(stroke
				(width 0.1524)
				(type default)
			)
			(layer "F.SilkS")
		)
		(fp_line
			(start -4.4958 -3.6322)
			(end -4.4958 -2.3622)
			(stroke
				(width 0.4064)
				(type default)
			)
			(layer "F.SilkS")
		)
		(fp_circle
			(center 3.24993 2.249932)
			(end 2.18313 2.249932)
			(stroke
				(width 0.3048)
				(type default)
			)
			(fill no)
			(layer "F.SilkS")
		)
		(fp_circle
			(center 3.24993 -2.249932)
			(end 2.18313 -2.249932)
			(stroke
				(width 0.3048)
				(type default)
			)
			(fill no)
			(layer "F.SilkS")
		)
		(fp_circle
			(center 0 0.762)
			(end -0.0762 0.762)
			(stroke
				(width 0.1524)
				(type default)
			)
			(fill no)
			(layer "F.SilkS")
		)
		(fp_circle
			(center 0 -0.762)
			(end -0.0762 -0.762)
			(stroke
				(width 0.1524)
				(type default)
			)
			(fill no)
			(layer "F.SilkS")
		)
		(fp_circle
			(center -3.24993 2.249932)
			(end -4.31673 2.249932)
			(stroke
				(width 0.3048)
				(type default)
			)
			(fill no)
			(layer "F.SilkS")
		)
		(fp_circle
			(center -3.24993 -2.249932)
			(end -4.31673 -2.249932)
			(stroke
				(width 0.3048)
				(type default)
			)
			(fill no)
			(layer "F.SilkS")
		)
		(fp_poly
			(pts
				(xy -3.0988 3.0988) (xy -3.0988 2.605532) (xy -3.9497 2.605532) (xy -3.9497 1.894332) (xy -3.0988 1.894332)
				(xy -3.0988 -1.894332) (xy -3.9497 -1.894332) (xy -3.9497 -2.605532) (xy -3.0988 -2.605532) (xy -3.0988 -3.0988)
				(xy 3.0988 -3.0988) (xy 3.0988 -2.605532) (xy 3.9497 -2.605532) (xy 3.9497 -1.894332) (xy 3.0988 -1.894332)
				(xy 3.0988 1.894332) (xy 3.9497 1.894332) (xy 3.9497 2.605532) (xy 3.0988 2.605532) (xy 3.0988 3.0988)
			)
			(stroke
				(width 0)
				(type default)
			)
			(fill no)
			(layer "F.CrtYd")
		)
		(fp_poly
			(pts
				(xy -4.4704 3.6068) (xy -4.4704 -3.6068) (xy 4.4704 -3.6068) (xy 4.4704 3.6068) (xy 0.00254 3.6068)
				(xy 0.00254 3.0988) (xy 3.0988 3.0988) (xy 3.0988 2.605532) (xy 3.9497 2.605532) (xy 3.9497 1.894332)
				(xy 3.0988 1.894332) (xy 3.0988 -1.894332) (xy 3.9497 -1.894332) (xy 3.9497 -2.605532) (xy 3.0988 -2.605532)
				(xy 3.0988 -3.0988) (xy -3.0988 -3.0988) (xy -3.0988 -2.605532) (xy -3.9497 -2.605532) (xy -3.9497 -1.894332)
				(xy -3.0988 -1.894332) (xy -3.0988 1.894332) (xy -3.9497 1.894332) (xy -3.9497 2.605532) (xy -3.0988 2.605532)
				(xy -3.0988 3.0988) (xy -0.00254 3.0988) (xy -0.00254 3.6068)
			)
			(stroke
				(width 0)
				(type default)
			)
			(fill no)
			(layer "F.CrtYd")
		)
		(fp_rect
			(start -4.4704 3.6068)
			(end 4.4704 -3.6068)
			(stroke
				(width 0)
				(type default)
			)
			(fill no)
			(layer "F.Fab")
		)
		(pad "1" thru_hole circle
			(at -3.24993 -2.249932 180)
			(size 1.4224 1.4224)
			(drill 1.016)
			(layers "*.Cu" "*.Mask")
			(remove_unused_layers no)
			(net "CPU_EXP_RST")
			(clearance 0.1524)
			(thermal_gap 0.1524)
		)
		(pad "2" thru_hole circle
			(at 3.24993 -2.249932 180)
			(size 1.4224 1.4224)
			(drill 1.016)
			(layers "*.Cu" "*.Mask")
			(remove_unused_layers no)
			(net "CPU_EXP_RST")
			(clearance 0.1524)
			(thermal_gap 0.1524)
		)
		(pad "3" thru_hole circle
			(at -3.24993 2.249932 180)
			(size 1.4224 1.4224)
			(drill 1.016)
			(layers "*.Cu" "*.Mask")
			(remove_unused_layers no)
			(net "GND")
			(clearance 0.1524)
			(thermal_gap 0.1524)
		)
		(pad "4" thru_hole circle
			(at 3.24993 2.249932 180)
			(size 1.4224 1.4224)
			(drill 1.016)
			(layers "*.Cu" "*.Mask")
			(remove_unused_layers no)
			(net "GND")
			(clearance 0.1524)
			(thermal_gap 0.1524)
		)
	)
	(footprint ""
		(layer "F.Cu")
		(at 186.554872 -195.271136 -90)
		(property "Reference" "R432"
			(at 0 0 270)
			(layer "F.SilkS")
			(hide yes)
			(effects
				(font
					(size 1.27 1.27)
				)
			)
		)
		(property "Value" "0R2J-2-GP"
			(at 0.064008 -3.993896 270)
			(unlocked yes)
			(layer "F.Fab")
			(hide yes)
			(effects
				(font
					(size 1.016 1.016)
					(thickness 0.1524)
				)
			)
		)
		(property "Device Type" "R402H16"
			(at 0.064008 -5.517896 270)
			(unlocked yes)
			(layer "F.Fab")
			(hide yes)
			(effects
				(font
					(size 1.016 1.016)
					(thickness 0.1524)
				)
			)
		)
		(duplicate_pad_numbers_are_jumpers no)
		(fp_line
			(start -0.508 -0.9398)
			(end -0.508 0.9398)
			(stroke
				(width 0.1524)
				(type default)
			)
			(layer "F.SilkS")
		)
		(fp_line
			(start 0.508 -0.9398)
			(end -0.508 -0.9398)
			(stroke
				(width 0.1524)
				(type default)
			)
			(layer "F.SilkS")
		)
		(fp_rect
			(start -0.508 0.9398)
			(end 0.508 -0.9398)
			(stroke
				(width 0)
				(type default)
			)
			(fill no)
			(layer "F.CrtYd")
		)
		(fp_rect
			(start -0.508 0.9398)
			(end 0.508 -0.9398)
			(stroke
				(width 0)
				(type default)
			)
			(fill no)
			(layer "F.Fab")
		)
		(pad "1" smd custom
			(at 0 -0.4445 270)
			(size 0.1397 0.1397)
			(layers "F.Cu" "F.Mask" "F.Paste")
			(net "SAS_I2C_C_BUF_SDA")
			(options
				(clearance outline)
				(anchor circle)
			)
			(primitives
				(gr_poly
					(pts
						(arc
							(start -0.1778 -0.2794)
							(mid -0.249642 -0.249642)
							(end -0.2794 -0.1778)
						)
						(arc
							(start -0.2794 0.1778)
							(mid -0.249642 0.249642)
							(end -0.1778 0.2794)
						)
						(arc
							(start 0.1778 0.2794)
							(mid 0.249642 0.249642)
							(end 0.2794 0.1778)
						)
						(arc
							(start 0.2794 -0.1778)
							(mid 0.249642 -0.249642)
							(end 0.1778 -0.2794)
						)
					)
					(width 0)
					(fill yes)
				)
			)
		)
		(pad "2" smd custom
			(at 0 0.4445 270)
			(size 0.1397 0.1397)
			(layers "F.Cu" "F.Mask" "F.Paste")
			(net "BMC_I2C_C_SDA")
			(options
				(clearance outline)
				(anchor circle)
			)
			(primitives
				(gr_poly
					(pts
						(arc
							(start -0.1778 -0.2794)
							(mid -0.249642 -0.249642)
							(end -0.2794 -0.1778)
						)
						(arc
							(start -0.2794 0.1778)
							(mid -0.249642 0.249642)
							(end -0.1778 0.2794)
						)
						(arc
							(start 0.1778 0.2794)
							(mid 0.249642 0.249642)
							(end 0.2794 0.1778)
						)
						(arc
							(start 0.2794 -0.1778)
							(mid 0.249642 -0.249642)
							(end 0.1778 -0.2794)
						)
					)
					(width 0)
					(fill yes)
				)
			)
		)
	)
)
